# BASEBOARD_FAB2 (Tioga Pass) — schematic netlist excerpt (pin names and nets, part order shuffled) for the footprints in the layout excerpt that follows; sources: Cadence DE-HDL packaged netlist, KiCad conversion of Wiwynn_Tioga_Pass_MB.brd

C5D4  CAP_A  22.0UF 4V 20% X6S  pkg 0603V  page 220 : A = PVDDQ_DEF ; B = GND
R7F10  RES  120.0 1% CHIP  pkg 0603  page 231 : A = PVPP_ABC ; B = GND
R12W33  RES  0.0 5% EMPTY  pkg 0402  page 223 : A = TP_PVDDQ_GHJ_MP2 ; B = PWRGD_PVDDQ_GHJ

(kicad_pcb
	(version 20260206)
	(generator "pcbnew")
	(generator_version "10.0")
	(general
		(thickness 1.6)
		(legacy_teardrops no)
	)
	(paper "A4")
	(title_block
		(title "Wiwynn_Tioga_Pass_MB.brd")
		(comment 1 "Tioga Pass / footprints 1713-1715 of 4770")
	)
	(layers
		(0 "F.Cu" signal "TOP")
		(4 "In1.Cu" signal "L2GND")
		(6 "In2.Cu" signal "L3")
		(8 "In3.Cu" signal "L4GND")
		(10 "In4.Cu" signal "L5")
		(12 "In5.Cu" signal "L6GND")
		(14 "In6.Cu" signal "L7VCC")
		(16 "In7.Cu" signal "L8VCC")
		(18 "In8.Cu" signal "L9GND")
		(20 "In9.Cu" signal "L10")
		(22 "In10.Cu" signal "L11GND")
		(24 "In11.Cu" signal "L12")
		(26 "In12.Cu" signal "L13GND")
		(2 "B.Cu" signal "BOTTOM")
		(9 "F.Adhes" user "F.Adhesive")
		(11 "B.Adhes" user "B.Adhesive")
		(13 "F.Paste" user "Package Geometry/Pastemask Top")
		(15 "B.Paste" user "Package Geometry/Pastemask Bottom")
		(5 "F.SilkS" user "Ref Des/Silkscreen Top")
		(7 "B.SilkS" user "Ref Des/Silkscreen Bottom")
		(1 "F.Mask" user "Board Geometry/Soldermask Top")
		(3 "B.Mask" user "Board Geometry/Soldermask Bottom")
		(17 "Dwgs.User" user "User.Drawings")
		(19 "Cmts.User" user "User.Comments")
		(21 "Eco1.User" user "User.Eco1")
		(23 "Eco2.User" user "User.Eco2")
		(25 "Edge.Cuts" user "Board Geometry/Outline")
		(27 "Margin" user)
		(31 "F.CrtYd" user "Package Geometry/Place Bound Top")
		(29 "B.CrtYd" user "Package Geometry/Place Bound Bottom")
		(35 "F.Fab" user "Ref Des/Assembly Top")
		(33 "B.Fab" user "Ref Des/Assembly Bottom")
	)
	(footprint ""
		(layer "F.Cu")
		(at 333.6798 -25.2603 90)
		(property "Reference" "R7F10"
			(at 0 0 90)
			(layer "F.SilkS")
			(hide yes)
			(effects
				(font
					(size 1.27 1.27)
				)
			)
		)
		(property "Value" ""
			(at 0 0 90)
			(layer "F.Fab")
			(effects
				(font
					(size 1.27 1.27)
				)
			)
		)
		(duplicate_pad_numbers_are_jumpers no)
		(fp_poly
			(pts
				(xy -0.4953 -0.2032) (xy 0.4953 -0.2032) (xy 0.4953 1.6002) (xy -0.4953 1.6002)
			)
			(stroke
				(width 0)
				(type default)
			)
			(fill no)
			(layer "F.CrtYd")
		)
		(fp_line
			(start 0.4953 -0.2032)
			(end 0.4953 1.6002)
			(stroke
				(width 0.1)
				(type default)
			)
			(layer "F.Fab")
		)
		(fp_line
			(start -0.4953 -0.2032)
			(end 0.4953 -0.2032)
			(stroke
				(width 0.1)
				(type default)
			)
			(layer "F.Fab")
		)
		(fp_line
			(start 0.4953 1.6002)
			(end -0.4953 1.6002)
			(stroke
				(width 0.1)
				(type default)
			)
			(layer "F.Fab")
		)
		(fp_line
			(start -0.4953 1.6002)
			(end -0.4953 -0.2032)
			(stroke
				(width 0.1)
				(type default)
			)
			(layer "F.Fab")
		)
		(pad "1" smd rect
			(at 0 0 90)
			(size 0.762 0.889)
			(layers "F.Cu" "F.Mask" "F.Paste")
			(net "PVPP_ABC")
		)
		(pad "2" smd rect
			(at 0 1.397 90)
			(size 0.762 0.889)
			(layers "F.Cu" "F.Mask" "F.Paste")
			(net "GND")
		)
		(zone
			(layer "F.Cu")
			(hatch none 0.5)
			(connect_pads
				(clearance 0)
			)
			(min_thickness 0.25)
			(keepout
				(tracks allowed)
				(vias not_allowed)
				(pads allowed)
				(copperpour not_allowed)
				(footprints allowed)
			)
			(placement
				(enabled no)
				(sheetname "")
			)
			(fill
				(thermal_gap 0.5)
				(thermal_bridge_width 0.5)
				(island_removal_mode 0)
			)
			(polygon
				(pts
					(xy 334.6323 -25.6413) (xy 334.1243 -25.6413) (xy 334.1243 -24.8793) (xy 334.6323 -24.8793)
				)
			)
		)
		(zone
			(layer "F.Cu")
			(hatch none 0.5)
			(connect_pads
				(clearance 0)
			)
			(min_thickness 0.25)
			(keepout
				(tracks not_allowed)
				(vias allowed)
				(pads allowed)
				(copperpour not_allowed)
				(footprints allowed)
			)
			(placement
				(enabled no)
				(sheetname "")
			)
			(fill
				(thermal_gap 0.5)
				(thermal_bridge_width 0.5)
				(island_removal_mode 0)
			)
			(polygon
				(pts
					(xy 334.6323 -24.8793) (xy 334.6323 -25.6413) (xy 334.1243 -25.6413) (xy 334.1243 -24.8793)
				)
			)
		)
	)
	(footprint ""
		(layer "F.Cu")
		(at 272.24101 -84.890102)
		(property "Reference" "C5D4"
			(at 0 0 0)
			(layer "F.SilkS")
			(hide yes)
			(effects
				(font
					(size 1.27 1.27)
				)
			)
		)
		(property "Value" ""
			(at 0 0 0)
			(layer "F.Fab")
			(effects
				(font
					(size 1.27 1.27)
				)
			)
		)
		(duplicate_pad_numbers_are_jumpers no)
		(fp_poly
			(pts
				(xy -0.4953 -0.2032) (xy 0.4953 -0.2032) (xy 0.4953 1.6002) (xy -0.4953 1.6002)
			)
			(stroke
				(width 0)
				(type default)
			)
			(fill no)
			(layer "F.CrtYd")
		)
		(fp_line
			(start -0.4953 -0.2032)
			(end 0.4953 -0.2032)
			(stroke
				(width 0.1)
				(type default)
			)
			(layer "F.Fab")
		)
		(fp_line
			(start -0.4953 1.6002)
			(end -0.4953 -0.2032)
			(stroke
				(width 0.1)
				(type default)
			)
			(layer "F.Fab")
		)
		(fp_line
			(start 0.4953 -0.2032)
			(end 0.4953 1.6002)
			(stroke
				(width 0.1)
				(type default)
			)
			(layer "F.Fab")
		)
		(fp_line
			(start 0.4953 1.6002)
			(end -0.4953 1.6002)
			(stroke
				(width 0.1)
				(type default)
			)
			(layer "F.Fab")
		)
		(pad "1" smd rect
			(at 0 0)
			(size 0.762 0.889)
			(layers "F.Cu" "F.Mask" "F.Paste")
			(net "PVDDQ_DEF")
		)
		(pad "2" smd rect
			(at 0 1.397)
			(size 0.762 0.889)
			(layers "F.Cu" "F.Mask" "F.Paste")
			(net "GND")
		)
		(zone
			(layer "F.Cu")
			(hatch none 0.5)
			(connect_pads
				(clearance 0)
			)
			(min_thickness 0.25)
			(keepout
				(tracks not_allowed)
				(vias allowed)
				(pads allowed)
				(copperpour not_allowed)
				(footprints allowed)
			)
			(placement
				(enabled no)
				(sheetname "")
			)
			(fill
				(thermal_gap 0.5)
				(thermal_bridge_width 0.5)
				(island_removal_mode 0)
			)
			(polygon
				(pts
					(xy 271.86001 -84.445602) (xy 272.62201 -84.445602) (xy 272.62201 -83.937602) (xy 271.86001 -83.937602)
				)
			)
		)
	)
	(footprint ""
		(layer "F.Cu")
		(at 8.818626 -3.357118 180)
		(property "Reference" "R12W33"
			(at -0.8382 -0.67818 180)
			(unlocked yes)
			(layer "F.SilkS")
			(effects
				(font
					(size 0.4064 0.254)
					(thickness 0.1524)
				)
				(justify left)
			)
		)
		(property "Value" ""
			(at 0 0 180)
			(layer "F.Fab")
			(effects
				(font
					(size 1.27 1.27)
				)
			)
		)
		(duplicate_pad_numbers_are_jumpers no)
		(fp_poly
			(pts
				(xy -0.2794 -0.1016) (xy 0.2794 -0.1016) (xy 0.2794 0.9906) (xy -0.2794 0.9906)
			)
			(stroke
				(width 0)
				(type default)
			)
			(fill no)
			(layer "F.CrtYd")
		)
		(fp_line
			(start 0.2794 0.9906)
			(end 0.2794 -0.1016)
			(stroke
				(width 0.1)
				(type default)
			)
			(layer "F.Fab")
		)
		(fp_line
			(start 0.2794 -0.1016)
			(end -0.2794 -0.1016)
			(stroke
				(width 0.1)
				(type default)
			)
			(layer "F.Fab")
		)
		(fp_line
			(start -0.2794 0.9906)
			(end 0.2794 0.9906)
			(stroke
				(width 0.1)
				(type default)
			)
			(layer "F.Fab")
		)
		(fp_line
			(start -0.2794 -0.1016)
			(end -0.2794 0.9906)
			(stroke
				(width 0.1)
				(type default)
			)
			(layer "F.Fab")
		)
		(pad "1" smd rect
			(at 0 0 180)
			(size 0.508 0.508)
			(layers "F.Cu" "F.Mask" "F.Paste")
			(net "TP_PVDDQ_GHJ_MP2")
		)
		(pad "2" smd rect
			(at 0 0.889 180)
			(size 0.508 0.508)
			(layers "F.Cu" "F.Mask" "F.Paste")
			(net "PWRGD_PVDDQ_GHJ")
		)
		(zone
			(layer "F.Cu")
			(hatch none 0.5)
			(connect_pads
				(clearance 0)
			)
			(min_thickness 0.25)
			(keepout
				(tracks not_allowed)
				(vias allowed)
				(pads allowed)
				(copperpour not_allowed)
				(footprints allowed)
			)
			(placement
				(enabled no)
				(sheetname "")
			)
			(fill
				(thermal_gap 0.5)
				(thermal_bridge_width 0.5)
				(island_removal_mode 0)
			)
			(polygon
				(pts
					(xy 9.072626 -3.992118) (xy 8.564626 -3.992118) (xy 8.564626 -3.611118) (xy 9.072626 -3.611118)
				)
			)
		)
		(zone
			(layer "F.Cu")
			(hatch none 0.5)
			(connect_pads
				(clearance 0)
			)
			(min_thickness 0.25)
			(keepout
				(tracks allowed)
				(vias not_allowed)
				(pads allowed)
				(copperpour not_allowed)
				(footprints allowed)
			)
			(placement
				(enabled no)
				(sheetname "")
			)
			(fill
				(thermal_gap 0.5)
				(thermal_bridge_width 0.5)
				(island_removal_mode 0)
			)
			(polygon
				(pts
					(xy 9.072626 -3.611118) (xy 8.564626 -3.611118) (xy 8.564626 -3.992118) (xy 9.072626 -3.992118)
				)
			)
		)
	)
)
